# S9S_MB_2U (Grand Teton) — schematic netlist excerpt (pin names and nets, part order shuffled) for the footprints in the layout excerpt that follows; sources: Cadence DE-HDL packaged netlist, KiCad conversion of 03242023_DA0F0TMBIJ0_F0T_Motherboard_J_brd_V01_OCP.brd

H112  GND_HOLE  EMPTY  pkg TH  page 311
  GND2  = GND
  GND3  = GND
  GND4  = GND
  GND5  = GND
  GND6  = GND
  GND7  = GND
  GND8  = GND
  GND9  = GND

(kicad_pcb
	(version 20260206)
	(generator "pcbnew")
	(generator_version "10.0")
	(general
		(thickness 1.6)
		(legacy_teardrops no)
	)
	(paper "A4")
	(title_block
		(title "03242023_DA0F0TMBIJ0_F0T_Motherboard_J_brd_V01_OCP.brd")
		(comment 1 "Grand Teton / footprints 2050-2050 of 6105")
	)
	(layers
		(0 "F.Cu" signal "TOP")
		(4 "In1.Cu" signal "GND")
		(6 "In2.Cu" signal "IN1")
		(8 "In3.Cu" signal "GND1")
		(10 "In4.Cu" signal "IN2")
		(12 "In5.Cu" signal "GND2")
		(14 "In6.Cu" signal "IN3")
		(16 "In7.Cu" signal "GND3")
		(18 "In8.Cu" signal "VCC")
		(20 "In9.Cu" signal "VCC1")
		(22 "In10.Cu" signal "GND4")
		(24 "In11.Cu" signal "IN4")
		(26 "In12.Cu" signal "GND5")
		(28 "In13.Cu" signal "IN5")
		(30 "In14.Cu" signal "GND6")
		(32 "In15.Cu" signal "IN6")
		(34 "In16.Cu" signal "GND7")
		(2 "B.Cu" signal "BOTTOM")
		(9 "F.Adhes" user "F.Adhesive")
		(11 "B.Adhes" user "B.Adhesive")
		(13 "F.Paste" user "Package Geometry/Pastemask Top")
		(15 "B.Paste" user "Package Geometry/Pastemask Bottom")
		(5 "F.SilkS" user "Ref Des/Silkscreen Top")
		(7 "B.SilkS" user "Ref Des/Silkscreen Bottom")
		(1 "F.Mask" user "Board Geometry/Soldermask Top")
		(3 "B.Mask" user "Board Geometry/Soldermask Bottom")
		(17 "Dwgs.User" user "User.Drawings")
		(19 "Cmts.User" user "User.Comments")
		(21 "Eco1.User" user "User.Eco1")
		(23 "Eco2.User" user "User.Eco2")
		(25 "Edge.Cuts" user "Board Geometry/Outline")
		(27 "Margin" user)
		(31 "F.CrtYd" user "Package Geometry/Place Bound Top")
		(29 "B.CrtYd" user "Package Geometry/Place Bound Bottom")
		(35 "F.Fab" user "Ref Des/Assembly Top")
		(33 "B.Fab" user "Ref Des/Assembly Bottom")
	)
	(footprint ""
		(layer "F.Cu")
		(at 204.64526 -51.999896)
		(property "Reference" "H112"
			(at -0.64008 -8.82777 0)
			(unlocked yes)
			(layer "F.SilkS")
			(effects
				(font
					(size 0.7874 0.5842)
					(thickness 0.1524)
				)
				(justify left)
			)
		)
		(property "Value" ""
			(at 0 0 0)
			(layer "F.Fab")
			(effects
				(font
					(size 1.27 1.27)
				)
			)
		)
		(duplicate_pad_numbers_are_jumpers no)
		(fp_arc
			(start -5.618226 -5.695188)
			(mid 3.086589 -7.380568)
			(end 7.999984 0)
			(stroke
				(width 0.1524)
				(type default)
			)
			(layer "F.SilkS")
		)
		(fp_arc
			(start 7.999984 0)
			(mid 3.083611 7.381777)
			(end -5.622798 5.690616)
			(stroke
				(width 0.1524)
				(type default)
			)
			(layer "F.SilkS")
		)
		(fp_arc
			(start -3.527044 -7.18058)
			(mid -2.158979 -7.703219)
			(end -0.718566 -7.967726)
			(stroke
				(width 0.1524)
				(type default)
			)
			(layer "B.SilkS")
		)
		(fp_arc
			(start 7.999984 0)
			(mid 3.091799 7.378252)
			(end -5.610098 5.703062)
			(stroke
				(width 0.1524)
				(type default)
			)
			(layer "B.SilkS")
		)
		(fp_circle
			(center 0 0)
			(end 7.999984 0)
			(stroke
				(width 0.1)
				(type default)
			)
			(fill no)
			(layer "B.Fab")
		)
		(fp_circle
			(center 0 0)
			(end 7.999984 0)
			(stroke
				(width 0.1)
				(type default)
			)
			(fill no)
			(layer "F.Fab")
		)
		(pad "" np_thru_hole circle
			(at 0 0)
			(size 5.5118 5.5118)
			(drill 5.5118)
			(layers "*.Cu" "*.Mask")
			(clearance 0.381)
			(thermal_gap 0.381)
		)
		(pad "2" thru_hole circle
			(at 0 -3.999992)
			(size 0.762 0.762)
			(drill 0.5588)
			(layers "*.Cu" "*.Mask")
			(remove_unused_layers no)
			(net "GND")
			(clearance 0.1524)
			(thermal_gap 0.1524)
		)
		(pad "3" thru_hole circle
			(at -2.999994 -2.500122)
			(size 0.762 0.762)
			(drill 0.5588)
			(layers "*.Cu" "*.Mask")
			(remove_unused_layers no)
			(net "GND")
			(clearance 0.1524)
			(thermal_gap 0.1524)
		)
		(pad "4" thru_hole circle
			(at -3.999992 0)
			(size 0.762 0.762)
			(drill 0.5588)
			(layers "*.Cu" "*.Mask")
			(remove_unused_layers no)
			(net "GND")
			(clearance 0.1524)
			(thermal_gap 0.1524)
		)
		(pad "5" thru_hole circle
			(at -2.999994 2.500122)
			(size 0.762 0.762)
			(drill 0.5588)
			(layers "*.Cu" "*.Mask")
			(remove_unused_layers no)
			(net "GND")
			(clearance 0.1524)
			(thermal_gap 0.1524)
		)
		(pad "6" thru_hole circle
			(at 0 3.999992)
			(size 0.762 0.762)
			(drill 0.5588)
			(layers "*.Cu" "*.Mask")
			(remove_unused_layers no)
			(net "GND")
			(clearance 0.1524)
			(thermal_gap 0.1524)
		)
		(pad "7" thru_hole circle
			(at 2.999994 2.500122)
			(size 0.762 0.762)
			(drill 0.5588)
			(layers "*.Cu" "*.Mask")
			(remove_unused_layers no)
			(net "GND")
			(clearance 0.1524)
			(thermal_gap 0.1524)
		)
		(pad "8" thru_hole circle
			(at 3.999992 0)
			(size 0.762 0.762)
			(drill 0.5588)
			(layers "*.Cu" "*.Mask")
			(remove_unused_layers no)
			(net "GND")
			(clearance 0.1524)
			(thermal_gap 0.1524)
		)
		(pad "9" thru_hole circle
			(at 2.999994 -2.500122)
			(size 0.762 0.762)
			(drill 0.5588)
			(layers "*.Cu" "*.Mask")
			(remove_unused_layers no)
			(net "GND")
			(clearance 0.1524)
			(thermal_gap 0.1524)
		)
		(zone
			(layer "F.Cu")
			(hatch none 0.5)
			(connect_pads
				(clearance 0)
			)
			(min_thickness 0.25)
			(keepout
				(tracks not_allowed)
				(vias allowed)
				(pads allowed)
				(copperpour not_allowed)
				(footprints allowed)
			)
			(placement
				(enabled no)
				(sheetname "")
			)
			(fill
				(thermal_gap 0.5)
				(thermal_bridge_width 0.5)
				(island_removal_mode 0)
			)
			(polygon
				(pts
					(arc
						(start 204.64526 -59.99988)
						(mid 198.988417 -57.656739)
						(end 196.645276 -51.999896)
					)
					(arc
						(start 196.645276 -51.999896)
						(mid 198.988417 -46.343053)
						(end 204.64526 -43.999912)
					)
					(xy 204.64526 -46.74616) (xy 204.594206 -46.74616)
					(arc
						(start 204.593952 -46.74616)
						(mid 199.391273 -51.999896)
						(end 204.593952 -57.253632)
					)
					(xy 204.594206 -57.253632) (xy 204.64526 -57.253632)
				)
			)
		)
		(zone
			(layer "F.Cu")
			(hatch none 0.5)
			(connect_pads
				(clearance 0)
			)
			(min_thickness 0.25)
			(keepout
				(tracks not_allowed)
				(vias allowed)
				(pads allowed)
				(copperpour not_allowed)
				(footprints allowed)
			)
			(placement
				(enabled no)
				(sheetname "")
			)
			(fill
				(thermal_gap 0.5)
				(thermal_bridge_width 0.5)
				(island_removal_mode 0)
			)
			(polygon
				(pts
					(arc
						(start 204.64526 -59.99988)
						(mid 210.302103 -57.656739)
						(end 212.645244 -51.999896)
					)
					(arc
						(start 212.645244 -51.999896)
						(mid 210.302103 -46.343053)
						(end 204.64526 -43.999912)
					)
					(xy 204.64526 -46.74616) (xy 204.696314 -46.74616)
					(arc
						(start 204.696568 -46.74616)
						(mid 209.899247 -51.999896)
						(end 204.696568 -57.253632)
					)
					(xy 204.696314 -57.253632) (xy 204.64526 -57.253632)
				)
			)
		)
		(zone
			(layers "F.Cu" "B.Cu" "In1.Cu" "In2.Cu" "In3.Cu" "In4.Cu" "In5.Cu" "In6.Cu"
				"In7.Cu" "In8.Cu" "In9.Cu" "In10.Cu" "In11.Cu" "In12.Cu" "In13.Cu" "In14.Cu"
				"In15.Cu" "In16.Cu"
			)
			(hatch none 0.5)
			(connect_pads
				(clearance 0)
			)
			(min_thickness 0.25)
			(keepout
				(tracks not_allowed)
				(vias allowed)
				(pads allowed)
				(copperpour not_allowed)
				(footprints allowed)
			)
			(placement
				(enabled no)
				(sheetname "")
			)
			(fill
				(thermal_gap 0.5)
				(thermal_bridge_width 0.5)
				(island_removal_mode 0)
			)
			(polygon
				(pts
					(arc
						(start 207.92186 -51.999896)
						(mid 201.36866 -51.999896)
						(end 207.92186 -51.999896)
					)
				)
			)
		)
		(zone
			(layer "B.Cu")
			(hatch none 0.5)
			(connect_pads
				(clearance 0)
			)
			(min_thickness 0.25)
			(keepout
				(tracks not_allowed)
				(vias allowed)
				(pads allowed)
				(copperpour not_allowed)
				(footprints allowed)
			)
			(placement
				(enabled no)
				(sheetname "")
			)
			(fill
				(thermal_gap 0.5)
				(thermal_bridge_width 0.5)
				(island_removal_mode 0)
			)
			(polygon
				(pts
					(arc
						(start 204.64526 -57.507886)
						(mid 199.13727 -51.999896)
						(end 204.64526 -46.491906)
					)
					(arc
						(start 204.64526 -46.974506)
						(mid 199.61987 -51.999896)
						(end 204.64526 -57.025286)
					)
				)
			)
		)
		(zone
			(layer "B.Cu")
			(hatch none 0.5)
			(connect_pads
				(clearance 0)
			)
			(min_thickness 0.25)
			(keepout
				(tracks not_allowed)
				(vias allowed)
				(pads allowed)
				(copperpour not_allowed)
				(footprints allowed)
			)
			(placement
				(enabled no)
				(sheetname "")
			)
			(fill
				(thermal_gap 0.5)
				(thermal_bridge_width 0.5)
				(island_removal_mode 0)
			)
			(polygon
				(pts
					(arc
						(start 204.64526 -57.507886)
						(mid 210.15325 -51.999896)
						(end 204.64526 -46.491906)
					)
					(arc
						(start 204.64526 -46.974506)
						(mid 209.67065 -51.999896)
						(end 204.64526 -57.025286)
					)
				)
			)
		)
	)
)
